(kicad_pcb
	(version 20260206)
	(generator "pcbnew")
	(generator_version "10.0")
	(general
		(thickness 1.6)
		(legacy_teardrops no)
	)
	(paper "A4")
	(title_block
		(title "04192023_DAF0TMB3IC0_F0TG_MB_C_brd_V02_OCP.brd")
		(comment 1 "Grand Teton / footprints 7068-7073 of 8354")
	)
	(layers
		(0 "F.Cu" signal "TOP")
		(4 "In1.Cu" signal "GND")
		(6 "In2.Cu" signal "IN1")
		(8 "In3.Cu" signal "GND1")
		(10 "In4.Cu" signal "IN2")
		(12 "In5.Cu" signal "GND2")
		(14 "In6.Cu" signal "IN3")
		(16 "In7.Cu" signal "GND3")
		(18 "In8.Cu" signal "VCC")
		(20 "In9.Cu" signal "VCC1")
		(22 "In10.Cu" signal "GND4")
		(24 "In11.Cu" signal "IN4")
		(26 "In12.Cu" signal "GND5")
		(28 "In13.Cu" signal "IN5")
		(30 "In14.Cu" signal "GND6")
		(32 "In15.Cu" signal "IN6")
		(34 "In16.Cu" signal "GND7")
		(2 "B.Cu" signal "BOTTOM")
		(9 "F.Adhes" user "F.Adhesive")
		(11 "B.Adhes" user "B.Adhesive")
		(13 "F.Paste" user "Package Geometry/Pastemask Top")
		(15 "B.Paste" user "Package Geometry/Pastemask Bottom")
		(5 "F.SilkS" user "Ref Des/Silkscreen Top")
		(7 "B.SilkS" user "Ref Des/Silkscreen Bottom")
		(1 "F.Mask" user "Board Geometry/Soldermask Top")
		(3 "B.Mask" user "Board Geometry/Soldermask Bottom")
		(17 "Dwgs.User" user "User.Drawings")
		(19 "Cmts.User" user "User.Comments")
		(21 "Eco1.User" user "User.Eco1")
		(23 "Eco2.User" user "User.Eco2")
		(25 "Edge.Cuts" user "Board Geometry/Outline")
		(27 "Margin" user)
		(31 "F.CrtYd" user "Package Geometry/Place Bound Top")
		(29 "B.CrtYd" user "Package Geometry/Place Bound Bottom")
		(35 "F.Fab" user "Ref Des/Assembly Top")
		(33 "B.Fab" user "Ref Des/Assembly Bottom")
	)
	(footprint ""
		(layer "B.Cu")
		(at 307.34127 -195.95211 180)
		(property "Reference" "R1674"
			(at 0 0 0)
			(layer "B.SilkS")
			(hide yes)
			(effects
				(font
					(size 1.27 1.27)
				)
				(justify mirror)
			)
		)
		(property "Value" ""
			(at 0 0 0)
			(layer "B.Fab")
			(effects
				(font
					(size 1.27 1.27)
				)
				(justify mirror)
			)
		)
		(duplicate_pad_numbers_are_jumpers no)
		(fp_line
			(start 0.7874 0.4064)
			(end 0.7874 -0.4064)
			(stroke
				(width 0.1524)
				(type default)
			)
			(layer "B.SilkS")
		)
		(fp_line
			(start 0.7874 -0.4064)
			(end -0.7874 -0.4064)
			(stroke
				(width 0.1524)
				(type default)
			)
			(layer "B.SilkS")
		)
		(fp_line
			(start -0.7874 0.4064)
			(end 0.7874 0.4064)
			(stroke
				(width 0.1524)
				(type default)
			)
			(layer "B.SilkS")
		)
		(fp_line
			(start -0.7874 -0.4064)
			(end -0.7874 0.4064)
			(stroke
				(width 0.1524)
				(type default)
			)
			(layer "B.SilkS")
		)
		(fp_line
			(start 0.67945 0.3048)
			(end 0.67945 -0.305054)
			(stroke
				(width 0.1)
				(type default)
			)
			(layer "B.Fab")
		)
		(fp_line
			(start 0.67945 -0.305054)
			(end 0.12065 -0.305054)
			(stroke
				(width 0.1)
				(type default)
			)
			(layer "B.Fab")
		)
		(fp_line
			(start 0.12065 0.3048)
			(end 0.67945 0.3048)
			(stroke
				(width 0.1)
				(type default)
			)
			(layer "B.Fab")
		)
		(fp_line
			(start 0.12065 0.2794)
			(end 0.12065 0.3048)
			(stroke
				(width 0.1)
				(type default)
			)
			(layer "B.Fab")
		)
		(fp_line
			(start 0.12065 -0.2794)
			(end -0.12065 -0.2794)
			(stroke
				(width 0.1)
				(type default)
			)
			(layer "B.Fab")
		)
		(fp_line
			(start 0.12065 -0.305054)
			(end 0.12065 -0.2794)
			(stroke
				(width 0.1)
				(type default)
			)
			(layer "B.Fab")
		)
		(fp_line
			(start -0.120396 0.3048)
			(end -0.120396 0.2794)
			(stroke
				(width 0.1)
				(type default)
			)
			(layer "B.Fab")
		)
		(fp_line
			(start -0.120396 0.2794)
			(end 0.12065 0.2794)
			(stroke
				(width 0.1)
				(type default)
			)
			(layer "B.Fab")
		)
		(fp_line
			(start -0.12065 -0.2794)
			(end -0.12065 -0.3048)
			(stroke
				(width 0.1)
				(type default)
			)
			(layer "B.Fab")
		)
		(fp_line
			(start -0.12065 -0.3048)
			(end -0.67945 -0.3048)
			(stroke
				(width 0.1)
				(type default)
			)
			(layer "B.Fab")
		)
		(fp_line
			(start -0.67945 0.3048)
			(end -0.120396 0.3048)
			(stroke
				(width 0.1)
				(type default)
			)
			(layer "B.Fab")
		)
		(fp_line
			(start -0.67945 -0.3048)
			(end -0.67945 0.3048)
			(stroke
				(width 0.1)
				(type default)
			)
			(layer "B.Fab")
		)
		(pad "1" smd circle
			(at 0.40005 0)
			(size 0 0)
			(layers "B.Cu" "B.Mask" "B.Paste")
			(net "I3C_SPD_DDRAF_CPU0_SDA")
		)
		(pad "2" smd circle
			(at -0.40005 0)
			(size 0 0)
			(layers "B.Cu" "B.Mask" "B.Paste")
			(net "I3C_SPD_DDRA_CPU0_SDA")
		)
	)
	(footprint ""
		(layer "B.Cu")
		(at 129.305304 -33.654492)
		(property "Reference" "C6080"
			(at 0 0 0)
			(layer "B.SilkS")
			(hide yes)
			(effects
				(font
					(size 1.27 1.27)
				)
				(justify mirror)
			)
		)
		(property "Value" ""
			(at 0 0 0)
			(layer "B.Fab")
			(effects
				(font
					(size 1.27 1.27)
				)
				(justify mirror)
			)
		)
		(duplicate_pad_numbers_are_jumpers no)
		(fp_line
			(start -0.7874 -0.4064)
			(end -0.7874 0.4064)
			(stroke
				(width 0.1524)
				(type default)
			)
			(layer "B.SilkS")
		)
		(fp_line
			(start -0.7874 0.4064)
			(end 0.7874 0.4064)
			(stroke
				(width 0.1524)
				(type default)
			)
			(layer "B.SilkS")
		)
		(fp_line
			(start 0.7874 -0.4064)
			(end -0.7874 -0.4064)
			(stroke
				(width 0.1524)
				(type default)
			)
			(layer "B.SilkS")
		)
		(fp_line
			(start 0.7874 0.4064)
			(end 0.7874 -0.4064)
			(stroke
				(width 0.1524)
				(type default)
			)
			(layer "B.SilkS")
		)
		(fp_line
			(start -0.67945 -0.3048)
			(end -0.67945 0.3048)
			(stroke
				(width 0.1)
				(type default)
			)
			(layer "B.Fab")
		)
		(fp_line
			(start -0.67945 0.3048)
			(end -0.120396 0.3048)
			(stroke
				(width 0.1)
				(type default)
			)
			(layer "B.Fab")
		)
		(fp_line
			(start -0.12065 -0.3048)
			(end -0.67945 -0.3048)
			(stroke
				(width 0.1)
				(type default)
			)
			(layer "B.Fab")
		)
		(fp_line
			(start -0.12065 -0.2794)
			(end -0.12065 -0.3048)
			(stroke
				(width 0.1)
				(type default)
			)
			(layer "B.Fab")
		)
		(fp_line
			(start -0.120396 0.2794)
			(end 0.12065 0.2794)
			(stroke
				(width 0.1)
				(type default)
			)
			(layer "B.Fab")
		)
		(fp_line
			(start -0.120396 0.3048)
			(end -0.120396 0.2794)
			(stroke
				(width 0.1)
				(type default)
			)
			(layer "B.Fab")
		)
		(fp_line
			(start 0.12065 -0.305054)
			(end 0.12065 -0.2794)
			(stroke
				(width 0.1)
				(type default)
			)
			(layer "B.Fab")
		)
		(fp_line
			(start 0.12065 -0.2794)
			(end -0.12065 -0.2794)
			(stroke
				(width 0.1)
				(type default)
			)
			(layer "B.Fab")
		)
		(fp_line
			(start 0.12065 0.2794)
			(end 0.12065 0.3048)
			(stroke
				(width 0.1)
				(type default)
			)
			(layer "B.Fab")
		)
		(fp_line
			(start 0.12065 0.3048)
			(end 0.67945 0.3048)
			(stroke
				(width 0.1)
				(type default)
			)
			(layer "B.Fab")
		)
		(fp_line
			(start 0.67945 -0.305054)
			(end 0.12065 -0.305054)
			(stroke
				(width 0.1)
				(type default)
			)
			(layer "B.Fab")
		)
		(fp_line
			(start 0.67945 0.3048)
			(end 0.67945 -0.305054)
			(stroke
				(width 0.1)
				(type default)
			)
			(layer "B.Fab")
		)
		(pad "1" smd circle
			(at 0.40005 0 180)
			(size 0 0)
			(layers "B.Cu" "B.Mask" "B.Paste")
			(net "P1V2_AUX")
		)
		(pad "2" smd circle
			(at -0.40005 0 180)
			(size 0 0)
			(layers "B.Cu" "B.Mask" "B.Paste")
			(net "GND")
		)
	)
	(footprint ""
		(layer "B.Cu")
		(at 373.337328 -137.008108 -90)
		(property "Reference" "R8308"
			(at 0 0 90)
			(layer "B.SilkS")
			(hide yes)
			(effects
				(font
					(size 1.27 1.27)
				)
				(justify mirror)
			)
		)
		(property "Value" ""
			(at 0 0 90)
			(layer "B.Fab")
			(effects
				(font
					(size 1.27 1.27)
				)
				(justify mirror)
			)
		)
		(duplicate_pad_numbers_are_jumpers no)
		(fp_line
			(start -0.7874 0.4064)
			(end 0.7874 0.4064)
			(stroke
				(width 0.1524)
				(type default)
			)
			(layer "B.SilkS")
		)
		(fp_line
			(start 0.7874 0.4064)
			(end 0.7874 -0.4064)
			(stroke
				(width 0.1524)
				(type default)
			)
			(layer "B.SilkS")
		)
		(fp_line
			(start -0.7874 -0.4064)
			(end -0.7874 0.4064)
			(stroke
				(width 0.1524)
				(type default)
			)
			(layer "B.SilkS")
		)
		(fp_line
			(start 0.7874 -0.4064)
			(end -0.7874 -0.4064)
			(stroke
				(width 0.1524)
				(type default)
			)
			(layer "B.SilkS")
		)
		(fp_line
			(start -0.67945 0.3048)
			(end -0.120396 0.3048)
			(stroke
				(width 0.1)
				(type default)
			)
			(layer "B.Fab")
		)
		(fp_line
			(start -0.120396 0.3048)
			(end -0.120396 0.2794)
			(stroke
				(width 0.1)
				(type default)
			)
			(layer "B.Fab")
		)
		(fp_line
			(start 0.12065 0.3048)
			(end 0.67945 0.3048)
			(stroke
				(width 0.1)
				(type default)
			)
			(layer "B.Fab")
		)
		(fp_line
			(start 0.67945 0.3048)
			(end 0.67945 -0.305054)
			(stroke
				(width 0.1)
				(type default)
			)
			(layer "B.Fab")
		)
		(fp_line
			(start -0.120396 0.2794)
			(end 0.12065 0.2794)
			(stroke
				(width 0.1)
				(type default)
			)
			(layer "B.Fab")
		)
		(fp_line
			(start 0.12065 0.2794)
			(end 0.12065 0.3048)
			(stroke
				(width 0.1)
				(type default)
			)
			(layer "B.Fab")
		)
		(fp_line
			(start -0.12065 -0.2794)
			(end -0.12065 -0.3048)
			(stroke
				(width 0.1)
				(type default)
			)
			(layer "B.Fab")
		)
		(fp_line
			(start 0.12065 -0.2794)
			(end -0.12065 -0.2794)
			(stroke
				(width 0.1)
				(type default)
			)
			(layer "B.Fab")
		)
		(fp_line
			(start -0.67945 -0.3048)
			(end -0.67945 0.3048)
			(stroke
				(width 0.1)
				(type default)
			)
			(layer "B.Fab")
		)
		(fp_line
			(start -0.12065 -0.3048)
			(end -0.67945 -0.3048)
			(stroke
				(width 0.1)
				(type default)
			)
			(layer "B.Fab")
		)
		(fp_line
			(start 0.12065 -0.305054)
			(end 0.12065 -0.2794)
			(stroke
				(width 0.1)
				(type default)
			)
			(layer "B.Fab")
		)
		(fp_line
			(start 0.67945 -0.305054)
			(end 0.12065 -0.305054)
			(stroke
				(width 0.1)
				(type default)
			)
			(layer "B.Fab")
		)
		(pad "1" smd circle
			(at 0.40005 0 90)
			(size 0 0)
			(layers "B.Cu" "B.Mask" "B.Paste")
			(net "SMB_SCM_2_R3_SCL")
		)
		(pad "2" smd circle
			(at -0.40005 0 90)
			(size 0 0)
			(layers "B.Cu" "B.Mask" "B.Paste")
			(net "PVDDCR_CPU0_P0_PMSCL_R")
		)
	)
	(footprint ""
		(layer "B.Cu")
		(at 363.215936 -256.012188 -90)
		(property "Reference" "C2539"
			(at 0 0 90)
			(layer "B.SilkS")
			(hide yes)
			(effects
				(font
					(size 1.27 1.27)
				)
				(justify mirror)
			)
		)
		(property "Value" ""
			(at 0 0 90)
			(layer "B.Fab")
			(effects
				(font
					(size 1.27 1.27)
				)
				(justify mirror)
			)
		)
		(duplicate_pad_numbers_are_jumpers no)
		(fp_line
			(start -0.7874 0.4064)
			(end 0.7874 0.4064)
			(stroke
				(width 0.1524)
				(type default)
			)
			(layer "B.SilkS")
		)
		(fp_line
			(start 0.7874 0.4064)
			(end 0.7874 -0.4064)
			(stroke
				(width 0.1524)
				(type default)
			)
			(layer "B.SilkS")
		)
		(fp_line
			(start -0.7874 -0.4064)
			(end -0.7874 0.4064)
			(stroke
				(width 0.1524)
				(type default)
			)
			(layer "B.SilkS")
		)
		(fp_line
			(start 0.7874 -0.4064)
			(end -0.7874 -0.4064)
			(stroke
				(width 0.1524)
				(type default)
			)
			(layer "B.SilkS")
		)
		(fp_line
			(start -0.67945 0.3048)
			(end -0.120396 0.3048)
			(stroke
				(width 0.1)
				(type default)
			)
			(layer "B.Fab")
		)
		(fp_line
			(start -0.120396 0.3048)
			(end -0.120396 0.2794)
			(stroke
				(width 0.1)
				(type default)
			)
			(layer "B.Fab")
		)
		(fp_line
			(start 0.12065 0.3048)
			(end 0.67945 0.3048)
			(stroke
				(width 0.1)
				(type default)
			)
			(layer "B.Fab")
		)
		(fp_line
			(start 0.67945 0.3048)
			(end 0.67945 -0.305054)
			(stroke
				(width 0.1)
				(type default)
			)
			(layer "B.Fab")
		)
		(fp_line
			(start -0.120396 0.2794)
			(end 0.12065 0.2794)
			(stroke
				(width 0.1)
				(type default)
			)
			(layer "B.Fab")
		)
		(fp_line
			(start 0.12065 0.2794)
			(end 0.12065 0.3048)
			(stroke
				(width 0.1)
				(type default)
			)
			(layer "B.Fab")
		)
		(fp_line
			(start -0.12065 -0.2794)
			(end -0.12065 -0.3048)
			(stroke
				(width 0.1)
				(type default)
			)
			(layer "B.Fab")
		)
		(fp_line
			(start 0.12065 -0.2794)
			(end -0.12065 -0.2794)
			(stroke
				(width 0.1)
				(type default)
			)
			(layer "B.Fab")
		)
		(fp_line
			(start -0.67945 -0.3048)
			(end -0.67945 0.3048)
			(stroke
				(width 0.1)
				(type default)
			)
			(layer "B.Fab")
		)
		(fp_line
			(start -0.12065 -0.3048)
			(end -0.67945 -0.3048)
			(stroke
				(width 0.1)
				(type default)
			)
			(layer "B.Fab")
		)
		(fp_line
			(start 0.12065 -0.305054)
			(end 0.12065 -0.2794)
			(stroke
				(width 0.1)
				(type default)
			)
			(layer "B.Fab")
		)
		(fp_line
			(start 0.67945 -0.305054)
			(end 0.12065 -0.305054)
			(stroke
				(width 0.1)
				(type default)
			)
			(layer "B.Fab")
		)
		(pad "1" smd circle
			(at 0.40005 0 90)
			(size 0 0)
			(layers "B.Cu" "B.Mask" "B.Paste")
			(net "PVDDCR_SOC_P0")
		)
		(pad "2" smd circle
			(at -0.40005 0 90)
			(size 0 0)
			(layers "B.Cu" "B.Mask" "B.Paste")
			(net "GND")
		)
	)
	(footprint ""
		(layer "B.Cu")
		(at 403.315678 -323.892672)
		(property "Reference" "R472"
			(at 0 0 0)
			(layer "B.SilkS")
			(hide yes)
			(effects
				(font
					(size 1.27 1.27)
				)
				(justify mirror)
			)
		)
		(property "Value" ""
			(at 0 0 0)
			(layer "B.Fab")
			(effects
				(font
					(size 1.27 1.27)
				)
				(justify mirror)
			)
		)
		(duplicate_pad_numbers_are_jumpers no)
		(fp_line
			(start -0.7874 -0.4064)
			(end -0.7874 0.4064)
			(stroke
				(width 0.1524)
				(type default)
			)
			(layer "B.SilkS")
		)
		(fp_line
			(start -0.7874 0.4064)
			(end 0.7874 0.4064)
			(stroke
				(width 0.1524)
				(type default)
			)
			(layer "B.SilkS")
		)
		(fp_line
			(start 0.7874 -0.4064)
			(end -0.7874 -0.4064)
			(stroke
				(width 0.1524)
				(type default)
			)
			(layer "B.SilkS")
		)
		(fp_line
			(start 0.7874 0.4064)
			(end 0.7874 -0.4064)
			(stroke
				(width 0.1524)
				(type default)
			)
			(layer "B.SilkS")
		)
		(fp_line
			(start -0.67945 -0.3048)
			(end -0.67945 0.3048)
			(stroke
				(width 0.1)
				(type default)
			)
			(layer "B.Fab")
		)
		(fp_line
			(start -0.67945 0.3048)
			(end -0.120396 0.3048)
			(stroke
				(width 0.1)
				(type default)
			)
			(layer "B.Fab")
		)
		(fp_line
			(start -0.12065 -0.3048)
			(end -0.67945 -0.3048)
			(stroke
				(width 0.1)
				(type default)
			)
			(layer "B.Fab")
		)
		(fp_line
			(start -0.12065 -0.2794)
			(end -0.12065 -0.3048)
			(stroke
				(width 0.1)
				(type default)
			)
			(layer "B.Fab")
		)
		(fp_line
			(start -0.120396 0.2794)
			(end 0.12065 0.2794)
			(stroke
				(width 0.1)
				(type default)
			)
			(layer "B.Fab")
		)
		(fp_line
			(start -0.120396 0.3048)
			(end -0.120396 0.2794)
			(stroke
				(width 0.1)
				(type default)
			)
			(layer "B.Fab")
		)
		(fp_line
			(start 0.12065 -0.305054)
			(end 0.12065 -0.2794)
			(stroke
				(width 0.1)
				(type default)
			)
			(layer "B.Fab")
		)
		(fp_line
			(start 0.12065 -0.2794)
			(end -0.12065 -0.2794)
			(stroke
				(width 0.1)
				(type default)
			)
			(layer "B.Fab")
		)
		(fp_line
			(start 0.12065 0.2794)
			(end 0.12065 0.3048)
			(stroke
				(width 0.1)
				(type default)
			)
			(layer "B.Fab")
		)
		(fp_line
			(start 0.12065 0.3048)
			(end 0.67945 0.3048)
			(stroke
				(width 0.1)
				(type default)
			)
			(layer "B.Fab")
		)
		(fp_line
			(start 0.67945 -0.305054)
			(end 0.12065 -0.305054)
			(stroke
				(width 0.1)
				(type default)
			)
			(layer "B.Fab")
		)
		(fp_line
			(start 0.67945 0.3048)
			(end 0.67945 -0.305054)
			(stroke
				(width 0.1)
				(type default)
			)
			(layer "B.Fab")
		)
		(pad "1" smd rect
			(at 0.40005 0)
			(size 0.4572 0.508)
			(layers "B.Cu" "B.Mask" "B.Paste")
			(net "ESPI_CPU0_ALERT_P0_N")
		)
		(pad "2" smd rect
			(at -0.40005 0)
			(size 0.4572 0.508)
			(layers "B.Cu" "B.Mask" "B.Paste")
			(net "ESPI_CPU0_R_ALERT_N")
		)
	)
	(footprint ""
		(layer "B.Cu")
		(at 104.561386 -267.529564)
		(property "Reference" "C2394"
			(at 0 0 0)
			(layer "B.SilkS")
			(hide yes)
			(effects
				(font
					(size 1.27 1.27)
				)
				(justify mirror)
			)
		)
		(property "Value" ""
			(at 0 0 0)
			(layer "B.Fab")
			(effects
				(font
					(size 1.27 1.27)
				)
				(justify mirror)
			)
		)
		(duplicate_pad_numbers_are_jumpers no)
		(fp_line
			(start -0.7874 -0.4064)
			(end -0.7874 0.4064)
			(stroke
				(width 0.1524)
				(type default)
			)
			(layer "B.SilkS")
		)
		(fp_line
			(start -0.7874 0.4064)
			(end 0.7874 0.4064)
			(stroke
				(width 0.1524)
				(type default)
			)
			(layer "B.SilkS")
		)
		(fp_line
			(start 0.7874 -0.4064)
			(end -0.7874 -0.4064)
			(stroke
				(width 0.1524)
				(type default)
			)
			(layer "B.SilkS")
		)
		(fp_line
			(start 0.7874 0.4064)
			(end 0.7874 -0.4064)
			(stroke
				(width 0.1524)
				(type default)
			)
			(layer "B.SilkS")
		)
		(fp_line
			(start -0.67945 -0.3048)
			(end -0.67945 0.3048)
			(stroke
				(width 0.1)
				(type default)
			)
			(layer "B.Fab")
		)
		(fp_line
			(start -0.67945 0.3048)
			(end -0.120396 0.3048)
			(stroke
				(width 0.1)
				(type default)
			)
			(layer "B.Fab")
		)
		(fp_line
			(start -0.12065 -0.3048)
			(end -0.67945 -0.3048)
			(stroke
				(width 0.1)
				(type default)
			)
			(layer "B.Fab")
		)
		(fp_line
			(start -0.12065 -0.2794)
			(end -0.12065 -0.3048)
			(stroke
				(width 0.1)
				(type default)
			)
			(layer "B.Fab")
		)
		(fp_line
			(start -0.120396 0.2794)
			(end 0.12065 0.2794)
			(stroke
				(width 0.1)
				(type default)
			)
			(layer "B.Fab")
		)
		(fp_line
			(start -0.120396 0.3048)
			(end -0.120396 0.2794)
			(stroke
				(width 0.1)
				(type default)
			)
			(layer "B.Fab")
		)
		(fp_line
			(start 0.12065 -0.305054)
			(end 0.12065 -0.2794)
			(stroke
				(width 0.1)
				(type default)
			)
			(layer "B.Fab")
		)
		(fp_line
			(start 0.12065 -0.2794)
			(end -0.12065 -0.2794)
			(stroke
				(width 0.1)
				(type default)
			)
			(layer "B.Fab")
		)
		(fp_line
			(start 0.12065 0.2794)
			(end 0.12065 0.3048)
			(stroke
				(width 0.1)
				(type default)
			)
			(layer "B.Fab")
		)
		(fp_line
			(start 0.12065 0.3048)
			(end 0.67945 0.3048)
			(stroke
				(width 0.1)
				(type default)
			)
			(layer "B.Fab")
		)
		(fp_line
			(start 0.67945 -0.305054)
			(end 0.12065 -0.305054)
			(stroke
				(width 0.1)
				(type default)
			)
			(layer "B.Fab")
		)
		(fp_line
			(start 0.67945 0.3048)
			(end 0.67945 -0.305054)
			(stroke
				(width 0.1)
				(type default)
			)
			(layer "B.Fab")
		)
		(pad "1" smd circle
			(at 0.40005 0 180)
			(size 0 0)
			(layers "B.Cu" "B.Mask" "B.Paste")
			(net "PVDDCR_CPU1_P1")
		)
		(pad "2" smd circle
			(at -0.40005 0 180)
			(size 0 0)
			(layers "B.Cu" "B.Mask" "B.Paste")
			(net "GND")
		)
	)
)
